(kicad_pcb
	(version 20260206)
	(generator "pcbnew")
	(generator_version "10.0")
	(general
		(thickness 1.6)
		(legacy_teardrops no)
	)
	(paper "A4")
	(title_block
		(title "Wiwynn_Tioga_Pass_MB.brd")
		(comment 1 "Tioga Pass / footprints 2468-2475 of 4770")
	)
	(layers
		(0 "F.Cu" signal "TOP")
		(4 "In1.Cu" signal "L2GND")
		(6 "In2.Cu" signal "L3")
		(8 "In3.Cu" signal "L4GND")
		(10 "In4.Cu" signal "L5")
		(12 "In5.Cu" signal "L6GND")
		(14 "In6.Cu" signal "L7VCC")
		(16 "In7.Cu" signal "L8VCC")
		(18 "In8.Cu" signal "L9GND")
		(20 "In9.Cu" signal "L10")
		(22 "In10.Cu" signal "L11GND")
		(24 "In11.Cu" signal "L12")
		(26 "In12.Cu" signal "L13GND")
		(2 "B.Cu" signal "BOTTOM")
		(9 "F.Adhes" user "F.Adhesive")
		(11 "B.Adhes" user "B.Adhesive")
		(13 "F.Paste" user "Package Geometry/Pastemask Top")
		(15 "B.Paste" user "Package Geometry/Pastemask Bottom")
		(5 "F.SilkS" user "Ref Des/Silkscreen Top")
		(7 "B.SilkS" user "Ref Des/Silkscreen Bottom")
		(1 "F.Mask" user "Board Geometry/Soldermask Top")
		(3 "B.Mask" user "Board Geometry/Soldermask Bottom")
		(17 "Dwgs.User" user "User.Drawings")
		(19 "Cmts.User" user "User.Comments")
		(21 "Eco1.User" user "User.Eco1")
		(23 "Eco2.User" user "User.Eco2")
		(25 "Edge.Cuts" user "Board Geometry/Outline")
		(27 "Margin" user)
		(31 "F.CrtYd" user "Package Geometry/Place Bound Top")
		(29 "B.CrtYd" user "Package Geometry/Place Bound Bottom")
		(35 "F.Fab" user "Ref Des/Assembly Top")
		(33 "B.Fab" user "Ref Des/Assembly Bottom")
	)
	(footprint ""
		(layer "B.Cu")
		(at 377.2281 -36.83 180)
		(property "Reference" "R7E10"
			(at 0 0 0)
			(layer "B.SilkS")
			(hide yes)
			(effects
				(font
					(size 1.27 1.27)
				)
				(justify mirror)
			)
		)
		(property "Value" ""
			(at 0 0 0)
			(layer "B.Fab")
			(effects
				(font
					(size 1.27 1.27)
				)
				(justify mirror)
			)
		)
		(duplicate_pad_numbers_are_jumpers no)
		(fp_poly
			(pts
				(xy 0.2794 -0.1016) (xy -0.2794 -0.1016) (xy -0.2794 0.9906) (xy 0.2794 0.9906)
			)
			(stroke
				(width 0)
				(type default)
			)
			(fill no)
			(layer "B.CrtYd")
		)
		(fp_line
			(start 0.2794 0.9906)
			(end -0.2794 0.9906)
			(stroke
				(width 0.1)
				(type default)
			)
			(layer "B.Fab")
		)
		(fp_line
			(start 0.2794 -0.1016)
			(end 0.2794 0.9906)
			(stroke
				(width 0.1)
				(type default)
			)
			(layer "B.Fab")
		)
		(fp_line
			(start -0.2794 0.9906)
			(end -0.2794 -0.1016)
			(stroke
				(width 0.1)
				(type default)
			)
			(layer "B.Fab")
		)
		(fp_line
			(start -0.2794 -0.1016)
			(end 0.2794 -0.1016)
			(stroke
				(width 0.1)
				(type default)
			)
			(layer "B.Fab")
		)
		(pad "1" smd rect
			(at 0 0)
			(size 0.508 0.508)
			(layers "B.Cu" "B.Mask" "B.Paste")
			(net "P3V3")
		)
		(pad "2" smd rect
			(at 0 0.889)
			(size 0.508 0.508)
			(layers "B.Cu" "B.Mask" "B.Paste")
			(net "IRQ_CPU0_VRHOT")
		)
		(zone
			(layer "B.Cu")
			(hatch none 0.5)
			(connect_pads
				(clearance 0)
			)
			(min_thickness 0.25)
			(keepout
				(tracks not_allowed)
				(vias allowed)
				(pads allowed)
				(copperpour not_allowed)
				(footprints allowed)
			)
			(placement
				(enabled no)
				(sheetname "")
			)
			(fill
				(thermal_gap 0.5)
				(thermal_bridge_width 0.5)
				(island_removal_mode 0)
			)
			(polygon
				(pts
					(xy 376.9741 -37.465) (xy 377.4821 -37.465) (xy 377.4821 -37.084) (xy 376.9741 -37.084)
				)
			)
		)
		(zone
			(layer "B.Cu")
			(hatch none 0.5)
			(connect_pads
				(clearance 0)
			)
			(min_thickness 0.25)
			(keepout
				(tracks allowed)
				(vias not_allowed)
				(pads allowed)
				(copperpour not_allowed)
				(footprints allowed)
			)
			(placement
				(enabled no)
				(sheetname "")
			)
			(fill
				(thermal_gap 0.5)
				(thermal_bridge_width 0.5)
				(island_removal_mode 0)
			)
			(polygon
				(pts
					(xy 376.9741 -37.084) (xy 377.4821 -37.084) (xy 377.4821 -37.465) (xy 376.9741 -37.465)
				)
			)
		)
	)
	(footprint ""
		(layer "B.Cu")
		(at 377.7488 -154.457146)
		(property "Reference" "C3L11"
			(at 0 0 0)
			(layer "B.SilkS")
			(hide yes)
			(effects
				(font
					(size 1.27 1.27)
				)
				(justify mirror)
			)
		)
		(property "Value" ""
			(at 0 0 0)
			(layer "B.Fab")
			(effects
				(font
					(size 1.27 1.27)
				)
				(justify mirror)
			)
		)
		(duplicate_pad_numbers_are_jumpers no)
		(fp_poly
			(pts
				(xy 0.7239 -0.2159) (xy -0.7239 -0.2159) (xy -0.7239 1.9939) (xy 0.7239 1.9939)
			)
			(stroke
				(width 0)
				(type default)
			)
			(fill no)
			(layer "B.CrtYd")
		)
		(fp_line
			(start -0.7239 -0.2159)
			(end 0.7239 -0.2159)
			(stroke
				(width 0.1)
				(type default)
			)
			(layer "B.Fab")
		)
		(fp_line
			(start -0.7239 1.9939)
			(end -0.7239 -0.2159)
			(stroke
				(width 0.1)
				(type default)
			)
			(layer "B.Fab")
		)
		(fp_line
			(start 0.7239 -0.2159)
			(end 0.7239 1.9939)
			(stroke
				(width 0.1)
				(type default)
			)
			(layer "B.Fab")
		)
		(fp_line
			(start 0.7239 1.9939)
			(end -0.7239 1.9939)
			(stroke
				(width 0.1)
				(type default)
			)
			(layer "B.Fab")
		)
		(pad "1" smd rect
			(at 0 0 180)
			(size 1.27 1.016)
			(layers "B.Cu" "B.Mask" "B.Paste")
			(net "VR_FET_SW_P12V_STBY_PVDDQ_DEF")
		)
		(pad "2" smd rect
			(at 0 1.778 180)
			(size 1.27 1.016)
			(layers "B.Cu" "B.Mask" "B.Paste")
			(net "GND")
		)
		(zone
			(layer "B.Cu")
			(hatch none 0.5)
			(connect_pads
				(clearance 0)
			)
			(min_thickness 0.25)
			(keepout
				(tracks not_allowed)
				(vias allowed)
				(pads allowed)
				(copperpour not_allowed)
				(footprints allowed)
			)
			(placement
				(enabled no)
				(sheetname "")
			)
			(fill
				(thermal_gap 0.5)
				(thermal_bridge_width 0.5)
				(island_removal_mode 0)
			)
			(polygon
				(pts
					(xy 378.3838 -153.949146) (xy 377.1138 -153.949146) (xy 377.1138 -153.187146) (xy 378.3838 -153.187146)
				)
			)
		)
	)
	(footprint ""
		(layer "B.Cu")
		(at 402.2344 -23.114 90)
		(property "Reference" "R1U27"
			(at 0 0 90)
			(layer "B.SilkS")
			(hide yes)
			(effects
				(font
					(size 1.27 1.27)
				)
				(justify mirror)
			)
		)
		(property "Value" ""
			(at 0 0 90)
			(layer "B.Fab")
			(effects
				(font
					(size 1.27 1.27)
				)
				(justify mirror)
			)
		)
		(duplicate_pad_numbers_are_jumpers no)
		(fp_poly
			(pts
				(xy 0.2794 -0.1016) (xy -0.2794 -0.1016) (xy -0.2794 0.9906) (xy 0.2794 0.9906)
			)
			(stroke
				(width 0)
				(type default)
			)
			(fill no)
			(layer "B.CrtYd")
		)
		(fp_line
			(start 0.2794 -0.1016)
			(end 0.2794 0.9906)
			(stroke
				(width 0.1)
				(type default)
			)
			(layer "B.Fab")
		)
		(fp_line
			(start -0.2794 -0.1016)
			(end 0.2794 -0.1016)
			(stroke
				(width 0.1)
				(type default)
			)
			(layer "B.Fab")
		)
		(fp_line
			(start 0.2794 0.9906)
			(end -0.2794 0.9906)
			(stroke
				(width 0.1)
				(type default)
			)
			(layer "B.Fab")
		)
		(fp_line
			(start -0.2794 0.9906)
			(end -0.2794 -0.1016)
			(stroke
				(width 0.1)
				(type default)
			)
			(layer "B.Fab")
		)
		(pad "1" smd rect
			(at 0 0 270)
			(size 0.508 0.508)
			(layers "B.Cu" "B.Mask" "B.Paste")
			(net "A_P3V3_SCALED")
		)
		(pad "2" smd rect
			(at 0 0.889 270)
			(size 0.508 0.508)
			(layers "B.Cu" "B.Mask" "B.Paste")
			(net "GND")
		)
		(zone
			(layer "B.Cu")
			(hatch none 0.5)
			(connect_pads
				(clearance 0)
			)
			(min_thickness 0.25)
			(keepout
				(tracks allowed)
				(vias not_allowed)
				(pads allowed)
				(copperpour not_allowed)
				(footprints allowed)
			)
			(placement
				(enabled no)
				(sheetname "")
			)
			(fill
				(thermal_gap 0.5)
				(thermal_bridge_width 0.5)
				(island_removal_mode 0)
			)
			(polygon
				(pts
					(xy 402.4884 -23.368) (xy 402.4884 -22.86) (xy 402.8694 -22.86) (xy 402.8694 -23.368)
				)
			)
		)
		(zone
			(layer "B.Cu")
			(hatch none 0.5)
			(connect_pads
				(clearance 0)
			)
			(min_thickness 0.25)
			(keepout
				(tracks not_allowed)
				(vias allowed)
				(pads allowed)
				(copperpour not_allowed)
				(footprints allowed)
			)
			(placement
				(enabled no)
				(sheetname "")
			)
			(fill
				(thermal_gap 0.5)
				(thermal_bridge_width 0.5)
				(island_removal_mode 0)
			)
			(polygon
				(pts
					(xy 402.8694 -23.368) (xy 402.8694 -22.86) (xy 402.4884 -22.86) (xy 402.4884 -23.368)
				)
			)
		)
	)
	(footprint ""
		(layer "B.Cu")
		(at 406.680924 -114.9858 180)
		(property "Reference" "C2M17"
			(at 0 0 0)
			(layer "B.SilkS")
			(hide yes)
			(effects
				(font
					(size 1.27 1.27)
				)
				(justify mirror)
			)
		)
		(property "Value" ""
			(at 0 0 0)
			(layer "B.Fab")
			(effects
				(font
					(size 1.27 1.27)
				)
				(justify mirror)
			)
		)
		(duplicate_pad_numbers_are_jumpers no)
		(fp_poly
			(pts
				(xy 0.7239 -0.2159) (xy -0.7239 -0.2159) (xy -0.7239 1.9939) (xy 0.7239 1.9939)
			)
			(stroke
				(width 0)
				(type default)
			)
			(fill no)
			(layer "B.CrtYd")
		)
		(fp_line
			(start 0.7239 1.9939)
			(end -0.7239 1.9939)
			(stroke
				(width 0.1)
				(type default)
			)
			(layer "B.Fab")
		)
		(fp_line
			(start 0.7239 -0.2159)
			(end 0.7239 1.9939)
			(stroke
				(width 0.1)
				(type default)
			)
			(layer "B.Fab")
		)
		(fp_line
			(start -0.7239 1.9939)
			(end -0.7239 -0.2159)
			(stroke
				(width 0.1)
				(type default)
			)
			(layer "B.Fab")
		)
		(fp_line
			(start -0.7239 -0.2159)
			(end 0.7239 -0.2159)
			(stroke
				(width 0.1)
				(type default)
			)
			(layer "B.Fab")
		)
		(pad "1" smd rect
			(at 0 0)
			(size 1.27 1.016)
			(layers "B.Cu" "B.Mask" "B.Paste")
			(net "P1V05_PCH_STBY")
		)
		(pad "2" smd rect
			(at 0 1.778)
			(size 1.27 1.016)
			(layers "B.Cu" "B.Mask" "B.Paste")
			(net "GND")
		)
		(zone
			(layer "B.Cu")
			(hatch none 0.5)
			(connect_pads
				(clearance 0)
			)
			(min_thickness 0.25)
			(keepout
				(tracks not_allowed)
				(vias allowed)
				(pads allowed)
				(copperpour not_allowed)
				(footprints allowed)
			)
			(placement
				(enabled no)
				(sheetname "")
			)
			(fill
				(thermal_gap 0.5)
				(thermal_bridge_width 0.5)
				(island_removal_mode 0)
			)
			(polygon
				(pts
					(xy 406.045924 -115.4938) (xy 407.315924 -115.4938) (xy 407.315924 -116.2558) (xy 406.045924 -116.2558)
				)
			)
		)
	)
	(footprint ""
		(layer "B.Cu")
		(at 370.459 -62.357 180)
		(property "Reference" "R3R2"
			(at 0 0 0)
			(layer "B.SilkS")
			(hide yes)
			(effects
				(font
					(size 1.27 1.27)
				)
				(justify mirror)
			)
		)
		(property "Value" ""
			(at 0 0 0)
			(layer "B.Fab")
			(effects
				(font
					(size 1.27 1.27)
				)
				(justify mirror)
			)
		)
		(duplicate_pad_numbers_are_jumpers no)
		(fp_poly
			(pts
				(xy 0.2794 -0.1016) (xy -0.2794 -0.1016) (xy -0.2794 0.9906) (xy 0.2794 0.9906)
			)
			(stroke
				(width 0)
				(type default)
			)
			(fill no)
			(layer "B.CrtYd")
		)
		(fp_line
			(start 0.2794 0.9906)
			(end -0.2794 0.9906)
			(stroke
				(width 0.1)
				(type default)
			)
			(layer "B.Fab")
		)
		(fp_line
			(start 0.2794 -0.1016)
			(end 0.2794 0.9906)
			(stroke
				(width 0.1)
				(type default)
			)
			(layer "B.Fab")
		)
		(fp_line
			(start -0.2794 0.9906)
			(end -0.2794 -0.1016)
			(stroke
				(width 0.1)
				(type default)
			)
			(layer "B.Fab")
		)
		(fp_line
			(start -0.2794 -0.1016)
			(end 0.2794 -0.1016)
			(stroke
				(width 0.1)
				(type default)
			)
			(layer "B.Fab")
		)
		(pad "1" smd rect
			(at 0 0)
			(size 0.508 0.508)
			(layers "B.Cu" "B.Mask" "B.Paste")
			(net "H_CPU1_FIVR_FAULT_G")
		)
		(pad "2" smd rect
			(at 0 0.889)
			(size 0.508 0.508)
			(layers "B.Cu" "B.Mask" "B.Paste")
			(net "GND")
		)
		(zone
			(layer "B.Cu")
			(hatch none 0.5)
			(connect_pads
				(clearance 0)
			)
			(min_thickness 0.25)
			(keepout
				(tracks not_allowed)
				(vias allowed)
				(pads allowed)
				(copperpour not_allowed)
				(footprints allowed)
			)
			(placement
				(enabled no)
				(sheetname "")
			)
			(fill
				(thermal_gap 0.5)
				(thermal_bridge_width 0.5)
				(island_removal_mode 0)
			)
			(polygon
				(pts
					(xy 370.205 -62.992) (xy 370.713 -62.992) (xy 370.713 -62.611) (xy 370.205 -62.611)
				)
			)
		)
		(zone
			(layer "B.Cu")
			(hatch none 0.5)
			(connect_pads
				(clearance 0)
			)
			(min_thickness 0.25)
			(keepout
				(tracks allowed)
				(vias not_allowed)
				(pads allowed)
				(copperpour not_allowed)
				(footprints allowed)
			)
			(placement
				(enabled no)
				(sheetname "")
			)
			(fill
				(thermal_gap 0.5)
				(thermal_bridge_width 0.5)
				(island_removal_mode 0)
			)
			(polygon
				(pts
					(xy 370.205 -62.611) (xy 370.713 -62.611) (xy 370.713 -62.992) (xy 370.205 -62.992)
				)
			)
		)
	)
	(footprint ""
		(layer "B.Cu")
		(at 272.861532 -135.4074 90)
		(property "Reference" "C5M1"
			(at -1.848866 0.752348 90)
			(unlocked yes)
			(layer "B.SilkS")
			(effects
				(font
					(size 1.27 0.9652)
					(thickness 0.1524)
				)
				(justify mirror)
			)
		)
		(property "Value" ""
			(at 0 0 90)
			(layer "B.Fab")
			(effects
				(font
					(size 1.27 1.27)
				)
				(justify mirror)
			)
		)
		(duplicate_pad_numbers_are_jumpers no)
		(fp_rect
			(start 0.500126 1.598422)
			(end -0.500126 -0.201422)
			(stroke
				(width 0)
				(type default)
			)
			(fill no)
			(layer "B.CrtYd")
		)
		(fp_line
			(start 0.500126 -0.201422)
			(end -0.500126 -0.201422)
			(stroke
				(width 0.1)
				(type default)
			)
			(layer "B.Fab")
		)
		(fp_line
			(start -0.500126 -0.201422)
			(end -0.500126 1.598422)
			(stroke
				(width 0.1)
				(type default)
			)
			(layer "B.Fab")
		)
		(fp_line
			(start 0.500126 1.598422)
			(end 0.500126 -0.201422)
			(stroke
				(width 0.1)
				(type default)
			)
			(layer "B.Fab")
		)
		(fp_line
			(start -0.500126 1.598422)
			(end 0.500126 1.598422)
			(stroke
				(width 0.1)
				(type default)
			)
			(layer "B.Fab")
		)
		(pad "1" smd rect
			(at 0 0)
			(size 0.889 0.9906)
			(layers "B.Cu" "B.Mask" "B.Paste")
			(net "PVDDQ_DEF")
		)
		(pad "2" smd rect
			(at 0 1.397)
			(size 0.889 0.9906)
			(layers "B.Cu" "B.Mask" "B.Paste")
			(net "GND")
		)
		(zone
			(layer "B.Cu")
			(hatch none 0.5)
			(connect_pads
				(clearance 0)
			)
			(min_thickness 0.25)
			(keepout
				(tracks not_allowed)
				(vias allowed)
				(pads allowed)
				(copperpour not_allowed)
				(footprints allowed)
			)
			(placement
				(enabled no)
				(sheetname "")
			)
			(fill
				(thermal_gap 0.5)
				(thermal_bridge_width 0.5)
				(island_removal_mode 0)
			)
			(polygon
				(pts
					(xy 273.814032 -135.9027) (xy 273.306032 -135.9027) (xy 273.306032 -134.9121) (xy 273.814032 -134.9121)
				)
			)
		)
		(zone
			(layer "B.Cu")
			(hatch none 0.5)
			(connect_pads
				(clearance 0)
			)
			(min_thickness 0.25)
			(keepout
				(tracks allowed)
				(vias not_allowed)
				(pads allowed)
				(copperpour not_allowed)
				(footprints allowed)
			)
			(placement
				(enabled no)
				(sheetname "")
			)
			(fill
				(thermal_gap 0.5)
				(thermal_bridge_width 0.5)
				(island_removal_mode 0)
			)
			(polygon
				(pts
					(xy 273.814032 -135.9027) (xy 273.306032 -135.9027) (xy 273.306032 -134.9121) (xy 273.814032 -134.9121)
				)
			)
		)
	)
	(footprint ""
		(layer "B.Cu")
		(at 181.991 -12.7 180)
		(property "Reference" "C6U5"
			(at 0 0 0)
			(layer "B.SilkS")
			(hide yes)
			(effects
				(font
					(size 1.27 1.27)
				)
				(justify mirror)
			)
		)
		(property "Value" ""
			(at 0 0 0)
			(layer "B.Fab")
			(effects
				(font
					(size 1.27 1.27)
				)
				(justify mirror)
			)
		)
		(duplicate_pad_numbers_are_jumpers no)
		(fp_rect
			(start 0.3048 -0.1016)
			(end -0.3048 0.9906)
			(stroke
				(width 0)
				(type default)
			)
			(fill no)
			(layer "B.CrtYd")
		)
		(fp_line
			(start 0.3048 0.9906)
			(end -0.3048 0.9906)
			(stroke
				(width 0.1)
				(type default)
			)
			(layer "B.Fab")
		)
		(fp_line
			(start 0.3048 -0.1016)
			(end 0.3048 0.9906)
			(stroke
				(width 0.1)
				(type default)
			)
			(layer "B.Fab")
		)
		(fp_line
			(start -0.3048 0.9906)
			(end -0.3048 -0.1016)
			(stroke
				(width 0.1)
				(type default)
			)
			(layer "B.Fab")
		)
		(fp_line
			(start -0.3048 -0.1016)
			(end 0.3048 -0.1016)
			(stroke
				(width 0.1)
				(type default)
			)
			(layer "B.Fab")
		)
		(pad "1" smd rect
			(at 0 0)
			(size 0.508 0.508)
			(layers "B.Cu" "B.Mask" "B.Paste")
			(net "VR_FET_SW_P12V_STBY_PVPP_GHJ")
		)
		(pad "2" smd rect
			(at 0 0.889)
			(size 0.508 0.508)
			(layers "B.Cu" "B.Mask" "B.Paste")
			(net "GND")
		)
		(zone
			(layer "B.Cu")
			(hatch none 0.5)
			(connect_pads
				(clearance 0)
			)
			(min_thickness 0.25)
			(keepout
				(tracks allowed)
				(vias not_allowed)
				(pads allowed)
				(copperpour not_allowed)
				(footprints allowed)
			)
			(placement
				(enabled no)
				(sheetname "")
			)
			(fill
				(thermal_gap 0.5)
				(thermal_bridge_width 0.5)
				(island_removal_mode 0)
			)
			(polygon
				(pts
					(xy 181.737 -12.954) (xy 182.245 -12.954) (xy 182.245 -13.335) (xy 181.737 -13.335)
				)
			)
		)
		(zone
			(layer "B.Cu")
			(hatch none 0.5)
			(connect_pads
				(clearance 0)
			)
			(min_thickness 0.25)
			(keepout
				(tracks not_allowed)
				(vias allowed)
				(pads allowed)
				(copperpour not_allowed)
				(footprints allowed)
			)
			(placement
				(enabled no)
				(sheetname "")
			)
			(fill
				(thermal_gap 0.5)
				(thermal_bridge_width 0.5)
				(island_removal_mode 0)
			)
			(polygon
				(pts
					(xy 181.737 -12.954) (xy 182.245 -12.954) (xy 182.245 -13.335) (xy 181.737 -13.335)
				)
			)
		)
	)
	(footprint ""
		(layer "B.Cu")
		(at 17.272 -90.805)
		(property "Reference" "C9W1"
			(at 0 0 0)
			(layer "B.SilkS")
			(hide yes)
			(effects
				(font
					(size 1.27 1.27)
				)
				(justify mirror)
			)
		)
		(property "Value" "*"
			(at -1.1811 -2.8194 0)
			(unlocked yes)
			(layer "B.Fab")
			(hide yes)
			(effects
				(font
					(size 1.27 1.016)
					(thickness 0.1524)
				)
				(justify mirror)
			)
		)
		(property "Device Type" "SC22P50V2JN-4GP_SMD-BCG-SC22P5A"
			(at -1.1811 -4.3434 0)
			(unlocked yes)
			(layer "B.Fab")
			(hide yes)
			(effects
				(font
					(size 1.27 1.016)
					(thickness 0.1524)
				)
				(justify mirror)
			)
		)
		(duplicate_pad_numbers_are_jumpers no)
		(fp_rect
			(start 0.4318 0.9525)
			(end -0.4318 -0.9525)
			(stroke
				(width 0)
				(type default)
			)
			(fill no)
			(layer "B.CrtYd")
		)
		(fp_rect
			(start 0.4318 0.9525)
			(end -0.4318 -0.9525)
			(stroke
				(width 0)
				(type default)
			)
			(fill no)
			(layer "B.Fab")
		)
		(pad "1" smd custom
			(at 0 -0.4445 180)
			(size 0.1524 0.1524)
			(layers "B.Cu" "B.Mask" "B.Paste")
			(net "A_P12V_STBY_FP_TRIGGER")
			(options
				(clearance outline)
				(anchor circle)
			)
			(primitives
				(gr_poly
					(pts
						(arc
							(start 0.3048 0.2032)
							(mid 0.275042 0.275042)
							(end 0.2032 0.3048)
						)
						(arc
							(start -0.2032 0.3048)
							(mid -0.275042 0.275042)
							(end -0.3048 0.2032)
						)
						(arc
							(start -0.3048 -0.2032)
							(mid -0.275042 -0.275042)
							(end -0.2032 -0.3048)
						)
						(arc
							(start 0.2032 -0.3048)
							(mid 0.275042 -0.275042)
							(end 0.3048 -0.2032)
						)
					)
					(width 0)
					(fill yes)
				)
			)
		)
		(pad "2" smd custom
			(at 0 0.4445 180)
			(size 0.1524 0.1524)
			(layers "B.Cu" "B.Mask" "B.Paste")
			(net "AGND_HSC")
			(options
				(clearance outline)
				(anchor circle)
			)
			(primitives
				(gr_poly
					(pts
						(arc
							(start 0.3048 0.2032)
							(mid 0.275042 0.275042)
							(end 0.2032 0.3048)
						)
						(arc
							(start -0.2032 0.3048)
							(mid -0.275042 0.275042)
							(end -0.3048 0.2032)
						)
						(arc
							(start -0.3048 -0.2032)
							(mid -0.275042 -0.275042)
							(end -0.2032 -0.3048)
						)
						(arc
							(start 0.2032 -0.3048)
							(mid 0.275042 -0.275042)
							(end 0.3048 -0.2032)
						)
					)
					(width 0)
					(fill yes)
				)
			)
		)
	)
)
